(kicad_pcb
	(version 20241229)
	(generator "pcbnew")
	(generator_version "9.0")
	(general
		(thickness 1.61)
		(legacy_teardrops no)
	)
	(paper "A3")
	(title_block
		(title "RDIMM DDR5 Tester")
		(date "2026-05-21")
		(rev "2.2.0")
		(company "Antmicro")
		(comment 9 "footprints 187-189 of 796")
	)
	(layers
		(0 "F.Cu" signal)
		(4 "In1.Cu" power)
		(6 "In2.Cu" mixed)
		(8 "In3.Cu" power)
		(10 "In4.Cu" mixed)
		(12 "In5.Cu" power)
		(14 "In6.Cu" mixed)
		(16 "In7.Cu" power)
		(18 "In8.Cu" power)
		(20 "In9.Cu" mixed)
		(22 "In10.Cu" power)
		(2 "B.Cu" signal)
		(9 "F.Adhes" user "F.Adhesive")
		(11 "B.Adhes" user "B.Adhesive")
		(13 "F.Paste" user)
		(15 "B.Paste" user)
		(5 "F.SilkS" user "F.Silkscreen")
		(7 "B.SilkS" user "B.Silkscreen")
		(1 "F.Mask" user)
		(3 "B.Mask" user)
		(17 "Dwgs.User" user "User.Drawings")
		(19 "Cmts.User" user "User.Comments")
		(21 "Eco1.User" user "User.Eco1")
		(23 "Eco2.User" user "User.Eco2")
		(25 "Edge.Cuts" user)
		(27 "Margin" user)
		(31 "F.CrtYd" user "F.Courtyard")
		(29 "B.CrtYd" user "B.Courtyard")
		(35 "F.Fab" user)
		(33 "B.Fab" user)
	)
	(footprint "antmicro-footprints:NetTie-2_SMD_Pad0.127mm"
		(layer "F.Cu")
		(at 257.727 162.423998)
		(descr "Net tie, 2 pin, 0.127mm  SMD pads")
		(tags "net tie")
		(property "Reference" "NT8"
			(at -0.128 -1.345 0)
			(layer "F.SilkS")
			(hide yes)
			(effects
				(font
					(size 0.7 0.7)
					(thickness 0.15)
				)
				(justify left bottom)
			)
		)
		(property "Value" "Net-Tie_P0.127mm"
			(at 0 1.199 0)
			(layer "F.Fab")
			(effects
				(font
					(size 0.7 0.7)
					(thickness 0.15)
				)
				(justify left bottom)
			)
		)
		(property "MPN" ""
			(at 0 0 0)
			(unlocked yes)
			(layer "F.Fab")
			(hide yes)
			(effects
				(font
					(size 1 1)
					(thickness 0.15)
				)
			)
		)
		(property "Manufacturer" ""
			(at 0 0 0)
			(unlocked yes)
			(layer "F.Fab")
			(hide yes)
			(effects
				(font
					(size 1 1)
					(thickness 0.15)
				)
			)
		)
		(property "Author" "Antmicro"
			(at 0 0 0)
			(unlocked yes)
			(layer "F.Fab")
			(hide yes)
			(effects
				(font
					(size 1 1)
					(thickness 0.15)
				)
			)
		)
		(property "License" "Apache-2.0"
			(at 0 0 0)
			(unlocked yes)
			(layer "F.Fab")
			(hide yes)
			(effects
				(font
					(size 1 1)
					(thickness 0.15)
				)
			)
		)
		(property ki_fp_filters "Net*Tie*")
		(sheetname "/Supply/DC-DC IO/")
		(sheetfile "dc-dc-io.kicad_sch")
		(attr through_hole exclude_from_pos_files exclude_from_bom)
		(net_tie_pad_groups "1, 2")
		(fp_poly
			(pts
				(xy -0.0635 -0.0635) (xy 0.0625 -0.0635) (xy 0.0625 0.0635) (xy -0.0635 0.0635)
			)
			(stroke
				(width 0)
				(type solid)
			)
			(fill yes)
			(layer "F.Cu")
		)
		(fp_poly
			(pts
				(xy 0.2 -0.16) (xy 0.29 -0.07) (xy 0.29 0.07) (xy 0.2 0.16) (xy -0.2 0.16) (xy -0.29 0.07) (xy -0.29 -0.06)
				(xy -0.19 -0.16)
			)
			(stroke
				(width 0.05)
				(type solid)
			)
			(fill no)
			(layer "F.CrtYd")
		)
		(fp_text user "Author: Antmicro"
			(at -0.128 4.4 0)
			(layer "F.Fab")
			(effects
				(font
					(size 0.7 0.7)
					(thickness 0.15)
				)
				(justify left bottom)
			)
		)
		(fp_text user "${REFERENCE}"
			(at -0.128 3.2 0)
			(layer "F.Fab")
			(effects
				(font
					(size 0.7 0.7)
					(thickness 0.15)
				)
				(justify left bottom)
			)
		)
		(fp_text user "License: Apache-2.0"
			(at -0.128 5.6 0)
			(layer "F.Fab")
			(effects
				(font
					(size 0.7 0.7)
					(thickness 0.15)
				)
				(justify left bottom)
			)
		)
		(pad "1" smd roundrect
			(at -0.127 0 180)
			(size 0.127 0.127)
			(layers "F.Cu")
			(roundrect_rratio 0.5)
			(chamfer_ratio 0)
			(chamfer top_left bottom_left)
			(net 688 "/Supply/DC-DC IO/1V2_SEN_+")
			(pinfunction "1")
			(pintype "passive")
		)
		(pad "2" smd roundrect
			(at 0.126 0)
			(size 0.127 0.127)
			(layers "F.Cu")
			(roundrect_rratio 0.5)
			(chamfer_ratio 0)
			(chamfer top_left bottom_left)
			(net 159 "/Supply/DC-DC IO/1V2_local")
			(pinfunction "2")
			(pintype "passive")
		)
	)
	(footprint "antmicro-footprints:DHVQFN-14-1EP_2.5x3mm"
		(layer "F.Cu")
		(at 147.775499 170.134 -90)
		(property "Reference" "U13"
			(at 1.915 4.151 0)
			(layer "F.SilkS")
			(effects
				(font
					(size 0.7 0.7)
					(thickness 0.15)
				)
				(justify left bottom)
			)
		)
		(property "Value" "TXU0304BQAR"
			(at 0 2.898 90)
			(layer "F.Fab")
			(effects
				(font
					(size 0.7 0.7)
					(thickness 0.15)
				)
				(justify right bottom)
			)
		)
		(property "Datasheet" "https://www.ti.com/lit/ds/symlink/txu0304.pdf?ts=1637748643258&ref_url=https%253A%252F%252Fwww.ti.com%252Fproduct%252FTXU0304"
			(at 0 0 270)
			(layer "F.Fab")
			(hide yes)
			(effects
				(font
					(size 1.27 1.27)
					(thickness 0.15)
				)
			)
		)
		(property "MPN" "TXU0304BQAR"
			(at 0 0 270)
			(unlocked yes)
			(layer "F.Fab")
			(hide yes)
			(effects
				(font
					(size 1 1)
					(thickness 0.15)
				)
			)
		)
		(property "Manufacturer" "Texas Instruments"
			(at 0 0 270)
			(unlocked yes)
			(layer "F.Fab")
			(hide yes)
			(effects
				(font
					(size 1 1)
					(thickness 0.15)
				)
			)
		)
		(property "Author" "Antmicro"
			(at 0 0 270)
			(unlocked yes)
			(layer "F.Fab")
			(hide yes)
			(effects
				(font
					(size 1 1)
					(thickness 0.15)
				)
			)
		)
		(property "License" "Apache-2.0"
			(at 0 0 270)
			(unlocked yes)
			(layer "F.Fab")
			(hide yes)
			(effects
				(font
					(size 1 1)
					(thickness 0.15)
				)
			)
		)
		(sheetname "/Debug FTDI + VNA/")
		(sheetfile "debug-ftdi.kicad_sch")
		(attr smd)
		(fp_line
			(start -1.35 1.6)
			(end -0.5 1.6)
			(stroke
				(width 0.15)
				(type solid)
			)
			(layer "F.SilkS")
		)
		(fp_line
			(start -1.35 1.6)
			(end -1.35 1.25)
			(stroke
				(width 0.15)
				(type solid)
			)
			(layer "F.SilkS")
		)
		(fp_line
			(start 0.5 1.6)
			(end 1.35 1.6)
			(stroke
				(width 0.15)
				(type solid)
			)
			(layer "F.SilkS")
		)
		(fp_line
			(start 1.35 1.6)
			(end 1.35 1.25)
			(stroke
				(width 0.15)
				(type solid)
			)
			(layer "F.SilkS")
		)
		(fp_line
			(start -1.35 -1.6)
			(end -1.35 -1.25)
			(stroke
				(width 0.15)
				(type solid)
			)
			(layer "F.SilkS")
		)
		(fp_line
			(start -1.35 -1.6)
			(end -0.5 -1.6)
			(stroke
				(width 0.15)
				(type solid)
			)
			(layer "F.SilkS")
		)
		(fp_line
			(start 1.35 -1.6)
			(end 1.35 -1.25)
			(stroke
				(width 0.15)
				(type solid)
			)
			(layer "F.SilkS")
		)
		(fp_line
			(start 1.35 -1.6)
			(end 0.5 -1.6)
			(stroke
				(width 0.15)
				(type solid)
			)
			(layer "F.SilkS")
		)
		(fp_circle
			(center -0.7 -1.85)
			(end -0.65 -1.85)
			(stroke
				(width 0.15)
				(type solid)
			)
			(fill yes)
			(layer "F.SilkS")
		)
		(fp_rect
			(start -1.8 -2)
			(end 1.8 2)
			(stroke
				(width 0.05)
				(type solid)
			)
			(fill no)
			(layer "F.CrtYd")
		)
		(fp_line
			(start -1.25 1.499)
			(end -1.25 -1.25)
			(stroke
				(width 0.15)
				(type solid)
			)
			(layer "F.Fab")
		)
		(fp_line
			(start 1.249 1.499)
			(end -1.25 1.499)
			(stroke
				(width 0.15)
				(type solid)
			)
			(layer "F.Fab")
		)
		(fp_line
			(start -1.25 -1.25)
			(end -1 -1.5)
			(stroke
				(width 0.15)
				(type solid)
			)
			(layer "F.Fab")
		)
		(fp_line
			(start -1 -1.5)
			(end 1.249 -1.5)
			(stroke
				(width 0.15)
				(type solid)
			)
			(layer "F.Fab")
		)
		(fp_line
			(start 1.249 -1.5)
			(end 1.249 1.499)
			(stroke
				(width 0.15)
				(type solid)
			)
			(layer "F.Fab")
		)
		(fp_text user "License: Apache-2.0"
			(at -1.841 6.097 270)
			(layer "F.Fab")
			(effects
				(font
					(size 0.7 0.7)
					(thickness 0.15)
				)
				(justify left bottom)
			)
		)
		(fp_text user "Author: Antmicro"
			(at -1.841 7.296 270)
			(layer "F.Fab")
			(effects
				(font
					(size 0.7 0.7)
					(thickness 0.15)
				)
				(justify left bottom)
			)
		)
		(fp_text user "${REFERENCE}"
			(at -1.841 4.897 270)
			(layer "F.Fab")
			(effects
				(font
					(size 0.7 0.7)
					(thickness 0.15)
				)
				(justify left bottom)
			)
		)
		(pad "1" smd oval
			(at -0.25 -1.5 270)
			(size 0.3 0.8)
			(layers "F.Cu" "F.Mask" "F.Paste")
			(net 6 "/Debug FTDI + VNA/FTDI_3V3")
			(pinfunction "VCCA")
			(pintype "power_in")
		)
		(pad "2" smd oval
			(at -1.25 -1)
			(size 0.3 0.8)
			(layers "F.Cu" "F.Mask" "F.Paste")
			(net 379 "/Debug FTDI + VNA/BDBUS0")
			(pinfunction "A1")
			(pintype "input")
		)
		(pad "3" smd oval
			(at -1.25 -0.5)
			(size 0.3 0.8)
			(layers "F.Cu" "F.Mask" "F.Paste")
			(net 1 "GND")
			(pinfunction "A2")
			(pintype "input")
		)
		(pad "4" smd oval
			(at -1.25 0)
			(size 0.3 0.8)
			(layers "F.Cu" "F.Mask" "F.Paste")
			(net 390 "/Debug FTDI + VNA/BDBUS1")
			(pinfunction "A3")
			(pintype "input")
		)
		(pad "5" smd oval
			(at -1.25 0.5)
			(size 0.3 0.8)
			(layers "F.Cu" "F.Mask" "F.Paste")
			(net 392 "/Debug FTDI + VNA/BDBUS2")
			(pinfunction "A4Y")
			(pintype "output")
		)
		(pad "6" smd oval
			(at -1.25 1)
			(size 0.3 0.8)
			(layers "F.Cu" "F.Mask" "F.Paste")
			(net 422 "unconnected-(U13-NC-Pad6)")
			(pinfunction "NC")
			(pintype "no_connect")
		)
		(pad "7" smd oval
			(at -0.25 1.5 270)
			(size 0.3 0.8)
			(layers "F.Cu" "F.Mask" "F.Paste")
			(net 1 "GND")
			(pinfunction "GND")
			(pintype "passive")
		)
		(pad "8" smd oval
			(at 0.25 1.5 270)
			(size 0.3 0.8)
			(layers "F.Cu" "F.Mask" "F.Paste")
			(net 301 "Net-(U13-OE)")
			(pinfunction "OE")
			(pintype "tri_state")
		)
		(pad "9" smd oval
			(at 1.25 1)
			(size 0.3 0.8)
			(layers "F.Cu" "F.Mask" "F.Paste")
			(net 423 "unconnected-(U13-NC-Pad9)")
			(pinfunction "NC")
			(pintype "no_connect")
		)
		(pad "10" smd oval
			(at 1.25 0.5)
			(size 0.3 0.8)
			(layers "F.Cu" "F.Mask" "F.Paste")
			(net 139 "/Debug FTDI + VNA/FTDI_SDA_IN")
			(pinfunction "B4")
			(pintype "input")
		)
		(pad "11" smd oval
			(at 1.25 0)
			(size 0.3 0.8)
			(layers "F.Cu" "F.Mask" "F.Paste")
			(net 44 "/Debug FTDI + VNA/FTDI_SDA_OUT")
			(pinfunction "B3Y")
			(pintype "output")
		)
		(pad "12" smd oval
			(at 1.25 -0.5)
			(size 0.3 0.8)
			(layers "F.Cu" "F.Mask" "F.Paste")
			(net 424 "unconnected-(U13-B2Y-Pad12)")
			(pinfunction "B2Y")
			(pintype "output+no_connect")
		)
		(pad "13" smd oval
			(at 1.25 -1)
			(size 0.3 0.8)
			(layers "F.Cu" "F.Mask" "F.Paste")
			(net 447 "/Debug FTDI + VNA/FTDI_SCL")
			(pinfunction "B1Y")
			(pintype "output")
		)
		(pad "14" smd oval
			(at 0.25 -1.5 270)
			(size 0.3 0.8)
			(layers "F.Cu" "F.Mask" "F.Paste")
			(net 38 "+3V3_AON")
			(pinfunction "VCCB")
			(pintype "power_in")
		)
		(pad "15" smd rect
			(at 0 0 270)
			(size 1 1.5)
			(layers "F.Cu" "F.Mask" "F.Paste")
			(net 1 "GND")
			(pinfunction "GND")
			(pintype "power_in")
		)
	)
	(footprint "antmicro-footprints:DFN-10-1EP_3x3mm"
		(layer "F.Cu")
		(at 239.274499 175.75)
		(property "Reference" "U3"
			(at -1.049499 3.025 0)
			(layer "F.SilkS")
			(effects
				(font
					(size 0.7 0.7)
					(thickness 0.15)
				)
				(justify left bottom)
			)
		)
		(property "Value" "PAC1720-1"
			(at 0 2.8 0)
			(layer "F.Fab")
			(effects
				(font
					(size 0.7 0.7)
					(thickness 0.15)
				)
				(justify left bottom)
			)
		)
		(property "Datasheet" "https://ww1.microchip.com/downloads/aemDocuments/documents/MSLD/ProductDocuments/DataSheets/PAC1710-PAC1720-Data-Sheet-DS20005386.pdf"
			(at 0 0 0)
			(layer "F.Fab")
			(hide yes)
			(effects
				(font
					(size 1.27 1.27)
					(thickness 0.15)
				)
			)
		)
		(property "MPN" "PAC1720-1-AIA-TR"
			(at 0 0 0)
			(unlocked yes)
			(layer "F.Fab")
			(hide yes)
			(effects
				(font
					(size 1 1)
					(thickness 0.15)
				)
			)
		)
		(property "Manufacturer" "Microchip Technology"
			(at 0 0 0)
			(unlocked yes)
			(layer "F.Fab")
			(hide yes)
			(effects
				(font
					(size 1 1)
					(thickness 0.15)
				)
			)
		)
		(property "Author" "Antmicro"
			(at 0 0 0)
			(unlocked yes)
			(layer "F.Fab")
			(hide yes)
			(effects
				(font
					(size 1 1)
					(thickness 0.15)
				)
			)
		)
		(property "License" "Apache-2.0"
			(at 0 0 0)
			(unlocked yes)
			(layer "F.Fab")
			(hide yes)
			(effects
				(font
					(size 1 1)
					(thickness 0.15)
				)
			)
		)
		(property ki_fp_filters "UQFN*1EP*4x4mm*P0.65mm*")
		(sheetname "/Supply/DC-DC AUX, MGT/")
		(sheetfile "dc-dc-aux-mgt.kicad_sch")
		(attr smd)
		(fp_line
			(start -1.624 -1.226)
			(end -1.773 -1.226)
			(stroke
				(width 0.15)
				(type solid)
			)
			(layer "F.SilkS")
		)
		(fp_line
			(start -1.6 1.6)
			(end -1.6 1.35)
			(stroke
				(width 0.15)
				(type solid)
			)
			(layer "F.SilkS")
		)
		(fp_line
			(start -1.6 1.6)
			(end -1.35 1.6)
			(stroke
				(width 0.15)
				(type solid)
			)
			(layer "F.SilkS")
		)
		(fp_line
			(start -1.249 -1.601)
			(end -1.624 -1.226)
			(stroke
				(width 0.15)
				(type solid)
			)
			(layer "F.SilkS")
		)
		(fp_line
			(start -1.249 -1.601)
			(end -0.824 -1.601)
			(stroke
				(width 0.15)
				(type solid)
			)
			(layer "F.SilkS")
		)
		(fp_line
			(start 1.601 -1.601)
			(end 1.351 -1.601)
			(stroke
				(width 0.15)
				(type solid)
			)
			(layer "F.SilkS")
		)
		(fp_line
			(start 1.601 -1.601)
			(end 1.601 -1.401)
			(stroke
				(width 0.15)
				(type solid)
			)
			(layer "F.SilkS")
		)
		(fp_line
			(start 1.601 1.6)
			(end 1.401 1.6)
			(stroke
				(width 0.15)
				(type solid)
			)
			(layer "F.SilkS")
		)
		(fp_line
			(start 1.601 1.6)
			(end 1.601 1.35)
			(stroke
				(width 0.15)
				(type solid)
			)
			(layer "F.SilkS")
		)
		(fp_circle
			(center -1.8 -1.6)
			(end -1.8 -1.551)
			(stroke
				(width 0.15)
				(type solid)
			)
			(fill yes)
			(layer "F.SilkS")
		)
		(fp_line
			(start -1.91 -1.73)
			(end 1.89 -1.73)
			(stroke
				(width 0.05)
				(type solid)
			)
			(layer "F.CrtYd")
		)
		(fp_line
			(start -1.91 1.75)
			(end -1.91 -1.73)
			(stroke
				(width 0.05)
				(type solid)
			)
			(layer "F.CrtYd")
		)
		(fp_line
			(start 1.89 1.75)
			(end -1.91 1.75)
			(stroke
				(width 0.05)
				(type solid)
			)
			(layer "F.CrtYd")
		)
		(fp_line
			(start 1.89 1.75)
			(end 1.89 -1.73)
			(stroke
				(width 0.05)
				(type solid)
			)
			(layer "F.CrtYd")
		)
		(fp_line
			(start -1.499 -1.18)
			(end -1.179 -1.5)
			(stroke
				(width 0.15)
				(type solid)
			)
			(layer "F.Fab")
		)
		(fp_line
			(start -1.499 1.499)
			(end -1.499 -1.176)
			(stroke
				(width 0.15)
				(type solid)
			)
			(layer "F.Fab")
		)
		(fp_line
			(start 1.5 -1.5)
			(end -1.175 -1.5)
			(stroke
				(width 0.15)
				(type solid)
			)
			(layer "F.Fab")
		)
		(fp_line
			(start 1.5 -1.5)
			(end 1.5 1.499)
			(stroke
				(width 0.15)
				(type solid)
			)
			(layer "F.Fab")
		)
		(fp_line
			(start 1.5 1.499)
			(end -1.499 1.499)
			(stroke
				(width 0.15)
				(type solid)
			)
			(layer "F.Fab")
		)
		(fp_text user "Author: Antmicro"
			(at -1.75 7.2 0)
			(layer "F.Fab")
			(effects
				(font
					(size 0.7 0.7)
					(thickness 0.15)
				)
				(justify left bottom)
			)
		)
		(fp_text user "${REFERENCE}"
			(at -1.75 5.999 0)
			(layer "F.Fab")
			(effects
				(font
					(size 0.7 0.7)
					(thickness 0.15)
				)
				(justify left bottom)
			)
		)
		(fp_text user "License: Apache-2.0"
			(at -1.75 8.4 0)
			(layer "F.Fab")
			(effects
				(font
					(size 0.7 0.7)
					(thickness 0.15)
				)
				(justify left bottom)
			)
		)
		(pad "1" smd roundrect
			(at -1.425 -1 270)
			(size 0.25 0.7)
			(layers "F.Cu" "F.Mask" "F.Paste")
			(roundrect_rratio 0.25)
			(net 681 "/Supply/DC-DC AUX, MGT/1V8_SEN_+")
			(pinfunction "IN1+")
			(pintype "input")
		)
		(pad "2" smd roundrect
			(at -1.425 -0.5 270)
			(size 0.25 0.7)
			(layers "F.Cu" "F.Mask" "F.Paste")
			(roundrect_rratio 0.25)
			(net 689 "/Supply/DC-DC AUX, MGT/1V8_SEN_-")
			(pinfunction "IN1-")
			(pintype "input")
		)
		(pad "3" smd roundrect
			(at -1.425 0 270)
			(size 0.25 0.7)
			(layers "F.Cu" "F.Mask" "F.Paste")
			(roundrect_rratio 0.25)
			(net 684 "/Supply/DC-DC AUX, MGT/MGTAVCCAUX_SEN_+")
			(pinfunction "IN2+")
			(pintype "input")
		)
		(pad "4" smd roundrect
			(at -1.425 0.498 270)
			(size 0.25 0.7)
			(layers "F.Cu" "F.Mask" "F.Paste")
			(roundrect_rratio 0.25)
			(net 692 "/Supply/DC-DC AUX, MGT/MGTAVCCAUX_SEN_-")
			(pinfunction "IN2-")
			(pintype "input")
		)
		(pad "5" smd roundrect
			(at -1.425 0.998 270)
			(size 0.25 0.7)
			(layers "F.Cu" "F.Mask" "F.Paste")
			(roundrect_rratio 0.25)
			(net 1 "GND")
			(pinfunction "GND")
			(pintype "power_in")
		)
		(pad "6" smd roundrect
			(at 1.426 0.998 270)
			(size 0.25 0.7)
			(layers "F.Cu" "F.Mask" "F.Paste")
			(roundrect_rratio 0.25)
			(net 729 "Net-(U3-ADDRSEL)")
			(pinfunction "ADDRSEL")
			(pintype "bidirectional")
		)
		(pad "7" smd roundrect
			(at 1.426 0.498 270)
			(size 0.25 0.7)
			(layers "F.Cu" "F.Mask" "F.Paste")
			(roundrect_rratio 0.25)
			(net 711 "Net-(U3-~{ALERT})")
			(pinfunction "~{ALERT}")
			(pintype "bidirectional")
		)
		(pad "8" smd roundrect
			(at 1.426 0 270)
			(size 0.25 0.7)
			(layers "F.Cu" "F.Mask" "F.Paste")
			(roundrect_rratio 0.25)
			(net 533 "/I^{2}C + I3C/PWR.SDA")
			(pinfunction "SDA")
			(pintype "bidirectional")
		)
		(pad "9" smd roundrect
			(at 1.426 -0.5 270)
			(size 0.25 0.7)
			(layers "F.Cu" "F.Mask" "F.Paste")
			(roundrect_rratio 0.25)
			(net 749 "/I^{2}C + I3C/PWR.SCL")
			(pinfunction "SCL")
			(pintype "input")
		)
		(pad "10" smd roundrect
			(at 1.426 -1 270)
			(size 0.25 0.7)
			(layers "F.Cu" "F.Mask" "F.Paste")
			(roundrect_rratio 0.25)
			(net 38 "+3V3_AON")
			(pinfunction "VDD")
			(pintype "power_in")
		)
		(pad "11" smd roundrect
			(at 0 0 270)
			(size 2.38 1.65)
			(layers "F.Cu" "F.Mask" "F.Paste")
			(roundrect_rratio 0.05)
			(net 1 "GND")
			(pinfunction "EP")
			(pintype "passive")
		)
	)
)
